# BASEBOARD_FAB2 (Tioga Pass) — schematic netlist excerpt (pin names and nets, part order shuffled) for the footprints in the layout excerpt that follows; sources: Cadence DE-HDL packaged netlist, KiCad conversion of Wiwynn_Tioga_Pass_MB.brd

TH1A1  MTG_KEYHOLE  EMPTY  pkg TH  page 195 : \1\ = GND
R1E7  RES  0.0 5% CHIP  pkg 0402  page 209 : A = VSENSE_PVCCIN_CPU1_N ; B = VSENSE_PVCCIN_CPU1_SKT_VRTN
R1D44  RES  0.0 5% CHIP  pkg 0402  page 200 : A = A_HSC_MOP ; B = A_HSC_HSP

(kicad_pcb
	(version 20260206)
	(generator "pcbnew")
	(generator_version "10.0")
	(general
		(thickness 1.6)
		(legacy_teardrops no)
	)
	(paper "A4")
	(title_block
		(title "Wiwynn_Tioga_Pass_MB.brd")
		(comment 1 "Tioga Pass / footprints 1202-1204 of 4770")
	)
	(layers
		(0 "F.Cu" signal "TOP")
		(4 "In1.Cu" signal "L2GND")
		(6 "In2.Cu" signal "L3")
		(8 "In3.Cu" signal "L4GND")
		(10 "In4.Cu" signal "L5")
		(12 "In5.Cu" signal "L6GND")
		(14 "In6.Cu" signal "L7VCC")
		(16 "In7.Cu" signal "L8VCC")
		(18 "In8.Cu" signal "L9GND")
		(20 "In9.Cu" signal "L10")
		(22 "In10.Cu" signal "L11GND")
		(24 "In11.Cu" signal "L12")
		(26 "In12.Cu" signal "L13GND")
		(2 "B.Cu" signal "BOTTOM")
		(9 "F.Adhes" user "F.Adhesive")
		(11 "B.Adhes" user "B.Adhesive")
		(13 "F.Paste" user "Package Geometry/Pastemask Top")
		(15 "B.Paste" user "Package Geometry/Pastemask Bottom")
		(5 "F.SilkS" user "Ref Des/Silkscreen Top")
		(7 "B.SilkS" user "Ref Des/Silkscreen Bottom")
		(1 "F.Mask" user "Board Geometry/Soldermask Top")
		(3 "B.Mask" user "Board Geometry/Soldermask Bottom")
		(17 "Dwgs.User" user "User.Drawings")
		(19 "Cmts.User" user "User.Comments")
		(21 "Eco1.User" user "User.Eco1")
		(23 "Eco2.User" user "User.Eco2")
		(25 "Edge.Cuts" user "Board Geometry/Outline")
		(27 "Margin" user)
		(31 "F.CrtYd" user "Package Geometry/Place Bound Top")
		(29 "B.CrtYd" user "Package Geometry/Place Bound Bottom")
		(35 "F.Fab" user "Ref Des/Assembly Top")
		(33 "B.Fab" user "Ref Des/Assembly Bottom")
	)
	(footprint ""
		(layer "F.Cu")
		(at 0 -155.10002 90)
		(property "Reference" "TH1A1"
			(at 2.45491 8.6868 0)
			(unlocked yes)
			(layer "F.SilkS")
			(effects
				(font
					(size 0.7874 0.5842)
					(thickness 0.1524)
				)
				(justify left)
			)
		)
		(property "Value" ""
			(at 0 0 90)
			(layer "F.Fab")
			(effects
				(font
					(size 1.27 1.27)
				)
			)
		)
		(duplicate_pad_numbers_are_jumpers no)
		(fp_poly
			(pts
				(arc
					(start 3.0226 0.68834)
					(mid 3.042235 0.827855)
					(end 3.099562 0.956564)
				)
				(arc
					(start 3.099562 0.956564)
					(mid 4.012804 3.550073)
					(end 3.042158 6.12267)
				)
				(arc
					(start 3.042158 6.12267)
					(mid 0 7.518589)
					(end -3.042158 6.12267)
				)
				(arc
					(start -3.042158 6.12267)
					(mid -4.012854 3.55061)
					(end -3.100324 0.957326)
				)
				(arc
					(start -3.100324 0.957326)
					(mid -3.042498 0.827518)
					(end -3.0226 0.686816)
				)
				(arc
					(start -3.0226 -0.000254)
					(mid -2.137121 -2.137227)
					(end 0 -3.022346)
				)
				(arc
					(start 0 -3.022346)
					(mid 2.137227 -2.136973)
					(end 3.0226 0.000254)
				)
			)
			(stroke
				(width 0)
				(type default)
			)
			(fill no)
			(layer "F.CrtYd")
		)
		(pad "1" thru_hole custom
			(at 0 0 90)
			(size 2.00667 2.00667)
			(drill 0.3048)
			(layers "*.Cu" "*.Mask")
			(remove_unused_layers no)
			(net "GND")
			(clearance -0.889)
			(options
				(clearance outline)
				(anchor circle)
			)
			(primitives
				(gr_poly
					(pts
						(arc
							(start 3.042158 3.874516)
							(mid 0 5.270435)
							(end -3.042158 3.874516)
						)
						(arc
							(start -3.042158 3.874516)
							(mid -4.012854 1.302456)
							(end -3.100324 -1.290828)
						)
						(arc
							(start -3.100324 -1.290828)
							(mid -3.042498 -1.420636)
							(end -3.0226 -1.561338)
						)
						(arc
							(start -3.0226 -2.248408)
							(mid -2.137121 -4.385381)
							(end 0 -5.2705)
						)
						(arc
							(start 0 -5.2705)
							(mid 2.137227 -4.385127)
							(end 3.0226 -2.2479)
						)
						(arc
							(start 3.0226 -1.55956)
							(mid 3.04227 -1.420177)
							(end 3.099562 -1.29159)
						)
						(arc
							(start 3.099562 -1.29159)
							(mid 4.012804 1.301919)
							(end 3.042158 3.874516)
						)
					)
					(width 0)
					(fill yes)
				)
			)
		)
	)
	(footprint ""
		(layer "F.Cu")
		(at 39.6748 -49.6824 90)
		(property "Reference" "R1E7"
			(at 0 0 90)
			(layer "F.SilkS")
			(hide yes)
			(effects
				(font
					(size 1.27 1.27)
				)
			)
		)
		(property "Value" ""
			(at 0 0 90)
			(layer "F.Fab")
			(effects
				(font
					(size 1.27 1.27)
				)
			)
		)
		(duplicate_pad_numbers_are_jumpers no)
		(fp_poly
			(pts
				(xy -0.2794 -0.1016) (xy 0.2794 -0.1016) (xy 0.2794 0.9906) (xy -0.2794 0.9906)
			)
			(stroke
				(width 0)
				(type default)
			)
			(fill no)
			(layer "F.CrtYd")
		)
		(fp_line
			(start 0.2794 -0.1016)
			(end -0.2794 -0.1016)
			(stroke
				(width 0.1)
				(type default)
			)
			(layer "F.Fab")
		)
		(fp_line
			(start -0.2794 -0.1016)
			(end -0.2794 0.9906)
			(stroke
				(width 0.1)
				(type default)
			)
			(layer "F.Fab")
		)
		(fp_line
			(start 0.2794 0.9906)
			(end 0.2794 -0.1016)
			(stroke
				(width 0.1)
				(type default)
			)
			(layer "F.Fab")
		)
		(fp_line
			(start -0.2794 0.9906)
			(end 0.2794 0.9906)
			(stroke
				(width 0.1)
				(type default)
			)
			(layer "F.Fab")
		)
		(pad "1" smd rect
			(at 0 0 90)
			(size 0.508 0.508)
			(layers "F.Cu" "F.Mask" "F.Paste")
			(net "VSENSE_PVCCIN_CPU1_N")
		)
		(pad "2" smd rect
			(at 0 0.889 90)
			(size 0.508 0.508)
			(layers "F.Cu" "F.Mask" "F.Paste")
			(net "VSENSE_PVCCIN_CPU1_SKT_VRTN")
		)
		(zone
			(layer "F.Cu")
			(hatch none 0.5)
			(connect_pads
				(clearance 0)
			)
			(min_thickness 0.25)
			(keepout
				(tracks allowed)
				(vias not_allowed)
				(pads allowed)
				(copperpour not_allowed)
				(footprints allowed)
			)
			(placement
				(enabled no)
				(sheetname "")
			)
			(fill
				(thermal_gap 0.5)
				(thermal_bridge_width 0.5)
				(island_removal_mode 0)
			)
			(polygon
				(pts
					(xy 39.9288 -49.4284) (xy 39.9288 -49.9364) (xy 40.3098 -49.9364) (xy 40.3098 -49.4284)
				)
			)
		)
		(zone
			(layer "F.Cu")
			(hatch none 0.5)
			(connect_pads
				(clearance 0)
			)
			(min_thickness 0.25)
			(keepout
				(tracks not_allowed)
				(vias allowed)
				(pads allowed)
				(copperpour not_allowed)
				(footprints allowed)
			)
			(placement
				(enabled no)
				(sheetname "")
			)
			(fill
				(thermal_gap 0.5)
				(thermal_bridge_width 0.5)
				(island_removal_mode 0)
			)
			(polygon
				(pts
					(xy 40.3098 -49.4284) (xy 40.3098 -49.9364) (xy 39.9288 -49.9364) (xy 39.9288 -49.4284)
				)
			)
		)
	)
	(footprint ""
		(layer "F.Cu")
		(at 14.224 -69.977 90)
		(property "Reference" "R1D44"
			(at 0 0 90)
			(layer "F.SilkS")
			(hide yes)
			(effects
				(font
					(size 1.27 1.27)
				)
			)
		)
		(property "Value" ""
			(at 0 0 90)
			(layer "F.Fab")
			(effects
				(font
					(size 1.27 1.27)
				)
			)
		)
		(duplicate_pad_numbers_are_jumpers no)
		(fp_rect
			(start -0.2794 0.9906)
			(end 0.2794 -0.1016)
			(stroke
				(width 0)
				(type default)
			)
			(fill no)
			(layer "F.CrtYd")
		)
		(fp_line
			(start 0.2794 -0.1016)
			(end -0.2794 -0.1016)
			(stroke
				(width 0.1)
				(type default)
			)
			(layer "F.Fab")
		)
		(fp_line
			(start -0.2794 -0.1016)
			(end -0.2794 0.9906)
			(stroke
				(width 0.1)
				(type default)
			)
			(layer "F.Fab")
		)
		(fp_line
			(start 0.2794 0.9906)
			(end 0.2794 -0.1016)
			(stroke
				(width 0.1)
				(type default)
			)
			(layer "F.Fab")
		)
		(fp_line
			(start -0.2794 0.9906)
			(end 0.2794 0.9906)
			(stroke
				(width 0.1)
				(type default)
			)
			(layer "F.Fab")
		)
		(pad "1" smd rect
			(at 0 0 90)
			(size 0.508 0.508)
			(layers "F.Cu" "F.Mask" "F.Paste")
			(net "A_HSC_MOP")
		)
		(pad "2" smd rect
			(at 0 0.889 90)
			(size 0.508 0.508)
			(layers "F.Cu" "F.Mask" "F.Paste")
			(net "A_HSC_HSP")
		)
		(zone
			(layer "F.Cu")
			(hatch none 0.5)
			(connect_pads
				(clearance 0)
			)
			(min_thickness 0.25)
			(keepout
				(tracks not_allowed)
				(vias allowed)
				(pads allowed)
				(copperpour not_allowed)
				(footprints allowed)
			)
			(placement
				(enabled no)
				(sheetname "")
			)
			(fill
				(thermal_gap 0.5)
				(thermal_bridge_width 0.5)
				(island_removal_mode 0)
			)
			(polygon
				(pts
					(xy 14.859 -69.723) (xy 14.859 -70.231) (xy 14.478 -70.231) (xy 14.478 -69.723)
				)
			)
		)
		(zone
			(layer "F.Cu")
			(hatch none 0.5)
			(connect_pads
				(clearance 0)
			)
			(min_thickness 0.25)
			(keepout
				(tracks allowed)
				(vias not_allowed)
				(pads allowed)
				(copperpour not_allowed)
				(footprints allowed)
			)
			(placement
				(enabled no)
				(sheetname "")
			)
			(fill
				(thermal_gap 0.5)
				(thermal_bridge_width 0.5)
				(island_removal_mode 0)
			)
			(polygon
				(pts
					(xy 14.859 -69.723) (xy 14.859 -70.231) (xy 14.478 -70.231) (xy 14.478 -69.723)
				)
			)
		)
	)
)
